(kicad_pcb
	(version 20221018)
	(generator pcbnew)
	(general
    (thickness 1.62)
  )
	(paper "A4")
	(title_block
    (title "ECP5 - Datacenter Secure Control Module (DC-SCM)")
    (date "2024-07-01")
    (rev "1.2.1")
		(comment 9 "footprints 491-498 of 506")
	)
	(layers
    (0 "F.Cu" signal)
    (1 "In1.Cu" power)
    (2 "In2.Cu" signal)
    (3 "In3.Cu" power)
    (4 "In4.Cu" power)
    (5 "In5.Cu" signal)
    (6 "In6.Cu" power)
    (31 "B.Cu" signal)
    (32 "B.Adhes" user "B.Adhesive")
    (33 "F.Adhes" user "F.Adhesive")
    (34 "B.Paste" user)
    (35 "F.Paste" user)
    (36 "B.SilkS" user "B.Silkscreen")
    (37 "F.SilkS" user "F.Silkscreen")
    (38 "B.Mask" user)
    (39 "F.Mask" user)
    (40 "Dwgs.User" user "User.Drawings")
    (41 "Cmts.User" user "User.Comments")
    (42 "Eco1.User" user "User.Eco1")
    (43 "Eco2.User" user "User.Eco2")
    (44 "Edge.Cuts" user)
    (45 "Margin" user)
    (46 "B.CrtYd" user "B.Courtyard")
    (47 "F.CrtYd" user "F.Courtyard")
    (48 "B.Fab" user)
    (49 "F.Fab" user)
  )
	(footprint "antmicro-footprints:C_0402_1005Metric" (layer "B.Cu")
    (at 138.1 86.325 90)
    (descr "Capacitor SMD 0402")
    (tags "capacitor SMD 0402")
    (property "Author" "Antmicro")
    (property "Dielectric" "X5R")
    (property "License" "Apache-2.0")
    (property "MPN" "GRM155R61H104KE14D")
    (property "Manufacturer" "Murata")
    (property "Public" "False")
    (property "Sheetfile" "interfaces.kicad_sch")
    (property "Sheetname" "Interfaces")
    (property "Val" "100n")
    (property "Voltage" "50V")
    (property "ki_description" "SMD Multilayer Ceramic Capacitor, 0.1 µF, 50 V, 0402 [1005 Metric], ± 10%, X5R, GRM Series")
    (property "ki_keywords" "0402, SMT, CAPACITOR, PASSIVE, CERAMIC, MLCC")
    (attr smd)
    (fp_text reference "C249" (at -3.04 -0.09 90) (layer "B.SilkS")
        (effects (font (size 0.7 0.7) (thickness 0.15)) (justify mirror))
    )
    (fp_text value "C_100n_0402" (at 0 -1.17 90) (layer "B.Fab")
        (effects (font (size 1 1) (thickness 0.15)) (justify mirror))
    )
    (fp_text user "Author: Antmicro" (at -0.939 -3.399 270) (layer "B.Fab") hide
        (effects (font (size 0.7 0.7) (thickness 0.15)) (justify left bottom mirror))
    )
    (fp_text user "License: Apache-2.0" (at -0.939 -5.799 270) (layer "B.Fab") hide
        (effects (font (size 0.7 0.7) (thickness 0.15)) (justify left bottom mirror))
    )
    (fp_text user "${REFERENCE}" (at 0 0 90) (layer "B.Fab")
        (effects (font (size 0.25 0.25) (thickness 0.04)) (justify mirror))
    )
    (fp_rect (start -0.925 0.47) (end 0.925 -0.47)
      (stroke (width 0.05) (type default)) (fill none) (layer "B.CrtYd"))
    (fp_line (start -0.494 -0.248) (end -0.494 0.25)
      (stroke (width 0.15) (type solid)) (layer "B.Fab"))
    (fp_line (start -0.494 0.25) (end 0.504 0.25)
      (stroke (width 0.15) (type solid)) (layer "B.Fab"))
    (fp_line (start 0.504 -0.248) (end -0.494 -0.248)
      (stroke (width 0.15) (type solid)) (layer "B.Fab"))
    (fp_line (start 0.504 0.25) (end 0.504 -0.248)
      (stroke (width 0.15) (type solid)) (layer "B.Fab"))
    (pad "1" smd roundrect (at -0.48 0 90) (size 0.59 0.64) (layers "B.Cu" "B.Paste" "B.Mask") (roundrect_rratio 0.25)
      (net 1 "GND") (pintype "passive"))
    (pad "2" smd roundrect (at 0.48 0 90) (size 0.59 0.64) (layers "B.Cu" "B.Paste" "B.Mask") (roundrect_rratio 0.25)
      (net 307 "Net-(U14-V_{PHY})") (pintype "passive"))
  )
	(footprint "antmicro-footprints:C_0402_1005Metric" (layer "B.Cu")
    (at 144.675 87.425 -90)
    (descr "Capacitor SMD 0402")
    (tags "capacitor SMD 0402")
    (property "Author" "Antmicro")
    (property "Dielectric" "X5R")
    (property "License" "Apache-2.0")
    (property "MPN" "GRM155R61H104KE14D")
    (property "Manufacturer" "Murata")
    (property "Public" "False")
    (property "Sheetfile" "interfaces.kicad_sch")
    (property "Sheetname" "Interfaces")
    (property "Val" "100n")
    (property "Voltage" "50V")
    (property "ki_description" "SMD Multilayer Ceramic Capacitor, 0.1 µF, 50 V, 0402 [1005 Metric], ± 10%, X5R, GRM Series")
    (property "ki_keywords" "0402, SMT, CAPACITOR, PASSIVE, CERAMIC, MLCC")
    (attr smd)
    (fp_text reference "C251" (at -0.34 1.025 90) (layer "B.SilkS")
        (effects (font (size 0.7 0.7) (thickness 0.15)) (justify mirror))
    )
    (fp_text value "C_100n_0402" (at 0 -1.17 90) (layer "B.Fab")
        (effects (font (size 1 1) (thickness 0.15)) (justify mirror))
    )
    (fp_text user "Author: Antmicro" (at -0.939 -3.399 90) (layer "B.Fab") hide
        (effects (font (size 0.7 0.7) (thickness 0.15)) (justify left bottom mirror))
    )
    (fp_text user "License: Apache-2.0" (at -0.939 -5.799 90) (layer "B.Fab") hide
        (effects (font (size 0.7 0.7) (thickness 0.15)) (justify left bottom mirror))
    )
    (fp_text user "${REFERENCE}" (at 0 0 90) (layer "B.Fab")
        (effects (font (size 0.25 0.25) (thickness 0.04)) (justify mirror))
    )
    (fp_rect (start -0.925 0.47) (end 0.925 -0.47)
      (stroke (width 0.05) (type default)) (fill none) (layer "B.CrtYd"))
    (fp_line (start -0.494 -0.248) (end -0.494 0.25)
      (stroke (width 0.15) (type solid)) (layer "B.Fab"))
    (fp_line (start -0.494 0.25) (end 0.504 0.25)
      (stroke (width 0.15) (type solid)) (layer "B.Fab"))
    (fp_line (start 0.504 -0.248) (end -0.494 -0.248)
      (stroke (width 0.15) (type solid)) (layer "B.Fab"))
    (fp_line (start 0.504 0.25) (end 0.504 -0.248)
      (stroke (width 0.15) (type solid)) (layer "B.Fab"))
    (pad "1" smd roundrect (at -0.48 0 270) (size 0.59 0.64) (layers "B.Cu" "B.Paste" "B.Mask") (roundrect_rratio 0.25)
      (net 1 "GND") (pintype "passive"))
    (pad "2" smd roundrect (at 0.48 0 270) (size 0.59 0.64) (layers "B.Cu" "B.Paste" "B.Mask") (roundrect_rratio 0.25)
      (net 2 "VCC3V3") (pintype "passive"))
  )
	(footprint "antmicro-footprints:C_0402_1005Metric" (layer "B.Cu")
    (at 135.1 86.325 90)
    (descr "Capacitor SMD 0402")
    (tags "capacitor SMD 0402")
    (property "Author" "Antmicro")
    (property "Dielectric" "")
    (property "License" "Apache-2.0")
    (property "MPN" "GRM155R61A475MEAAD")
    (property "Manufacturer" "Murata")
    (property "Public" "False")
    (property "Sheetfile" "interfaces.kicad_sch")
    (property "Sheetname" "Interfaces")
    (property "Val" "4u7")
    (property "Voltage" "")
    (property "ki_description" "SMD Multilayer Ceramic Capacitor, 4.7 µF, 10 V, 0402 [1005 Metric], ± 20%, X5R, GRM Series")
    (property "ki_keywords" "0402, SMT, CAPACITOR, PASSIVE")
    (attr smd)
    (fp_text reference "C250" (at -3.06 0.075 90) (layer "B.SilkS")
        (effects (font (size 0.7 0.7) (thickness 0.15)) (justify mirror))
    )
    (fp_text value "C_4u7_0402" (at 0 -1.17 90) (layer "B.Fab")
        (effects (font (size 1 1) (thickness 0.15)) (justify mirror))
    )
    (fp_text user "${REFERENCE}" (at 0 0 90) (layer "B.Fab")
        (effects (font (size 0.25 0.25) (thickness 0.04)) (justify mirror))
    )
    (fp_text user "License: Apache-2.0" (at -0.939 -5.799 270) (layer "B.Fab") hide
        (effects (font (size 0.7 0.7) (thickness 0.15)) (justify left bottom mirror))
    )
    (fp_text user "Author: Antmicro" (at -0.939 -3.399 270) (layer "B.Fab") hide
        (effects (font (size 0.7 0.7) (thickness 0.15)) (justify left bottom mirror))
    )
    (fp_rect (start -0.925 0.47) (end 0.925 -0.47)
      (stroke (width 0.05) (type default)) (fill none) (layer "B.CrtYd"))
    (fp_line (start -0.494 -0.248) (end -0.494 0.25)
      (stroke (width 0.15) (type solid)) (layer "B.Fab"))
    (fp_line (start -0.494 0.25) (end 0.504 0.25)
      (stroke (width 0.15) (type solid)) (layer "B.Fab"))
    (fp_line (start 0.504 -0.248) (end -0.494 -0.248)
      (stroke (width 0.15) (type solid)) (layer "B.Fab"))
    (fp_line (start 0.504 0.25) (end 0.504 -0.248)
      (stroke (width 0.15) (type solid)) (layer "B.Fab"))
    (pad "1" smd roundrect (at -0.48 0 90) (size 0.59 0.64) (layers "B.Cu" "B.Paste" "B.Mask") (roundrect_rratio 0.25)
      (net 1 "GND") (pintype "passive"))
    (pad "2" smd roundrect (at 0.48 0 90) (size 0.59 0.64) (layers "B.Cu" "B.Paste" "B.Mask") (roundrect_rratio 0.25)
      (net 306 "Net-(U14-V_{PLL})") (pintype "passive"))
  )
	(footprint "antmicro-footprints:C_0402_1005Metric" (layer "B.Cu")
    (at 136.1 86.325 90)
    (descr "Capacitor SMD 0402")
    (tags "capacitor SMD 0402")
    (property "Author" "Antmicro")
    (property "Dielectric" "X5R")
    (property "License" "Apache-2.0")
    (property "MPN" "GRM155R61H104KE14D")
    (property "Manufacturer" "Murata")
    (property "Public" "False")
    (property "Sheetfile" "interfaces.kicad_sch")
    (property "Sheetname" "Interfaces")
    (property "Val" "100n")
    (property "Voltage" "50V")
    (property "ki_description" "SMD Multilayer Ceramic Capacitor, 0.1 µF, 50 V, 0402 [1005 Metric], ± 10%, X5R, GRM Series")
    (property "ki_keywords" "0402, SMT, CAPACITOR, PASSIVE, CERAMIC, MLCC")
    (attr smd)
    (fp_text reference "C227" (at -3.04 0.01 90) (layer "B.SilkS")
        (effects (font (size 0.7 0.7) (thickness 0.15)) (justify mirror))
    )
    (fp_text value "C_100n_0402" (at 0 -1.17 90) (layer "B.Fab")
        (effects (font (size 1 1) (thickness 0.15)) (justify mirror))
    )
    (fp_text user "Author: Antmicro" (at -0.939 -3.399 270) (layer "B.Fab") hide
        (effects (font (size 0.7 0.7) (thickness 0.15)) (justify left bottom mirror))
    )
    (fp_text user "${REFERENCE}" (at 0 0 90) (layer "B.Fab")
        (effects (font (size 0.25 0.25) (thickness 0.04)) (justify mirror))
    )
    (fp_text user "License: Apache-2.0" (at -0.939 -5.799 270) (layer "B.Fab") hide
        (effects (font (size 0.7 0.7) (thickness 0.15)) (justify left bottom mirror))
    )
    (fp_rect (start -0.925 0.47) (end 0.925 -0.47)
      (stroke (width 0.05) (type default)) (fill none) (layer "B.CrtYd"))
    (fp_line (start -0.494 -0.248) (end -0.494 0.25)
      (stroke (width 0.15) (type solid)) (layer "B.Fab"))
    (fp_line (start -0.494 0.25) (end 0.504 0.25)
      (stroke (width 0.15) (type solid)) (layer "B.Fab"))
    (fp_line (start 0.504 -0.248) (end -0.494 -0.248)
      (stroke (width 0.15) (type solid)) (layer "B.Fab"))
    (fp_line (start 0.504 0.25) (end 0.504 -0.248)
      (stroke (width 0.15) (type solid)) (layer "B.Fab"))
    (pad "1" smd roundrect (at -0.48 0 90) (size 0.59 0.64) (layers "B.Cu" "B.Paste" "B.Mask") (roundrect_rratio 0.25)
      (net 1 "GND") (pintype "passive"))
    (pad "2" smd roundrect (at 0.48 0 90) (size 0.59 0.64) (layers "B.Cu" "B.Paste" "B.Mask") (roundrect_rratio 0.25)
      (net 306 "Net-(U14-V_{PLL})") (pintype "passive"))
  )
	(footprint "antmicro-footprints:C_0402_1005Metric" (layer "B.Cu")
    (at 140.415 89.775)
    (descr "Capacitor SMD 0402")
    (tags "capacitor SMD 0402")
    (property "Author" "Antmicro")
    (property "Dielectric" "X5R")
    (property "License" "Apache-2.0")
    (property "MPN" "GRM155R61H104KE14D")
    (property "Manufacturer" "Murata")
    (property "Public" "False")
    (property "Sheetfile" "interfaces.kicad_sch")
    (property "Sheetname" "Interfaces")
    (property "Val" "100n")
    (property "Voltage" "50V")
    (property "ki_description" "SMD Multilayer Ceramic Capacitor, 0.1 µF, 50 V, 0402 [1005 Metric], ± 10%, X5R, GRM Series")
    (property "ki_keywords" "0402, SMT, CAPACITOR, PASSIVE, CERAMIC, MLCC")
    (attr smd)
    (fp_text reference "C256" (at 0.055 1.42) (layer "B.SilkS")
        (effects (font (size 0.7 0.7) (thickness 0.15)) (justify mirror))
    )
    (fp_text value "C_100n_0402" (at 0 -1.17) (layer "B.Fab")
        (effects (font (size 1 1) (thickness 0.15)) (justify mirror))
    )
    (fp_text user "Author: Antmicro" (at -0.939 -3.399 180) (layer "B.Fab") hide
        (effects (font (size 0.7 0.7) (thickness 0.15)) (justify left bottom mirror))
    )
    (fp_text user "${REFERENCE}" (at 0 0) (layer "B.Fab")
        (effects (font (size 0.25 0.25) (thickness 0.04)) (justify mirror))
    )
    (fp_text user "License: Apache-2.0" (at -0.939 -5.799 180) (layer "B.Fab") hide
        (effects (font (size 0.7 0.7) (thickness 0.15)) (justify left bottom mirror))
    )
    (fp_rect (start -0.925 0.47) (end 0.925 -0.47)
      (stroke (width 0.05) (type default)) (fill none) (layer "B.CrtYd"))
    (fp_line (start -0.494 -0.248) (end -0.494 0.25)
      (stroke (width 0.15) (type solid)) (layer "B.Fab"))
    (fp_line (start -0.494 0.25) (end 0.504 0.25)
      (stroke (width 0.15) (type solid)) (layer "B.Fab"))
    (fp_line (start 0.504 -0.248) (end -0.494 -0.248)
      (stroke (width 0.15) (type solid)) (layer "B.Fab"))
    (fp_line (start 0.504 0.25) (end 0.504 -0.248)
      (stroke (width 0.15) (type solid)) (layer "B.Fab"))
    (pad "1" smd roundrect (at -0.48 0) (size 0.59 0.64) (layers "B.Cu" "B.Paste" "B.Mask") (roundrect_rratio 0.25)
      (net 1 "GND") (pintype "passive"))
    (pad "2" smd roundrect (at 0.48 0) (size 0.59 0.64) (layers "B.Cu" "B.Paste" "B.Mask") (roundrect_rratio 0.25)
      (net 2 "VCC3V3") (pintype "passive"))
  )
	(footprint "antmicro-footprints:C_0402_1005Metric" (layer "B.Cu")
    (at 129.65 115.525)
    (descr "Capacitor SMD 0402")
    (tags "capacitor SMD 0402")
    (property "Author" "Antmicro")
    (property "Dielectric" "X5R")
    (property "License" "Apache-2.0")
    (property "MPN" "GRM155R61H104KE14D")
    (property "Manufacturer" "Murata")
    (property "Public" "False")
    (property "Sheetfile" "interfaces.kicad_sch")
    (property "Sheetname" "Interfaces")
    (property "Val" "100n")
    (property "Voltage" "50V")
    (property "ki_description" "SMD Multilayer Ceramic Capacitor, 0.1 µF, 50 V, 0402 [1005 Metric], ± 10%, X5R, GRM Series")
    (property "ki_keywords" "0402, SMT, CAPACITOR, PASSIVE, CERAMIC, MLCC")
    (attr smd)
    (fp_text reference "C74" (at 2 -0.025 180) (layer "B.SilkS")
        (effects (font (size 0.7 0.7) (thickness 0.127)) (justify mirror))
    )
    (fp_text value "C_100n_0402" (at 0 -1.17) (layer "B.Fab")
        (effects (font (size 1 1) (thickness 0.15)) (justify mirror))
    )
    (fp_text user "${REFERENCE}" (at 0 0) (layer "B.Fab")
        (effects (font (size 0.25 0.25) (thickness 0.04)) (justify mirror))
    )
    (fp_text user "License: Apache-2.0" (at -0.939 -5.799 180) (layer "B.Fab") hide
        (effects (font (size 0.7 0.7) (thickness 0.15)) (justify left bottom mirror))
    )
    (fp_text user "Author: Antmicro" (at -0.939 -3.399 180) (layer "B.Fab") hide
        (effects (font (size 0.7 0.7) (thickness 0.15)) (justify left bottom mirror))
    )
    (fp_rect (start -0.925 0.47) (end 0.925 -0.47)
      (stroke (width 0.05) (type default)) (fill none) (layer "B.CrtYd"))
    (fp_line (start -0.494 -0.248) (end -0.494 0.25)
      (stroke (width 0.15) (type solid)) (layer "B.Fab"))
    (fp_line (start -0.494 0.25) (end 0.504 0.25)
      (stroke (width 0.15) (type solid)) (layer "B.Fab"))
    (fp_line (start 0.504 -0.248) (end -0.494 -0.248)
      (stroke (width 0.15) (type solid)) (layer "B.Fab"))
    (fp_line (start 0.504 0.25) (end 0.504 -0.248)
      (stroke (width 0.15) (type solid)) (layer "B.Fab"))
    (pad "1" smd roundrect (at -0.48 0) (size 0.59 0.64) (layers "B.Cu" "B.Paste" "B.Mask") (roundrect_rratio 0.25)
      (net 226 "Net-(U9-VDDA1.8)") (pintype "passive"))
    (pad "2" smd roundrect (at 0.48 0) (size 0.59 0.64) (layers "B.Cu" "B.Paste" "B.Mask") (roundrect_rratio 0.25)
      (net 1 "GND") (pintype "passive"))
  )
	(footprint "antmicro-footprints:C_0402_1005Metric" (layer "B.Cu")
    (at 81.715 125.095 90)
    (descr "Capacitor SMD 0402")
    (tags "capacitor SMD 0402")
    (property "Author" "Antmicro")
    (property "Dielectric" "")
    (property "License" "Apache-2.0")
    (property "MPN" "C1005X5R1E474M050BB")
    (property "Manufacturer" "TDK")
    (property "Public" "False")
    (property "Sheetfile" "ddr3.kicad_sch")
    (property "Sheetname" "DDR3")
    (property "Val" "470n")
    (property "Voltage" "")
    (property "ki_description" "SMD Multilayer Ceramic Capacitor, 0.47 µF, 25 V, 0402 [1005 Metric], ± 20%, X5R, C")
    (property "ki_keywords" "0402, SMT, CAPACITOR, PASSIVE, CERAMIC, MLCC")
    (attr smd)
    (fp_text reference "C91" (at -1.76 0.835 90) (layer "B.SilkS")
        (effects (font (size 0.7 0.7) (thickness 0.127)) (justify mirror))
    )
    (fp_text value "C_470n_0402" (at 0 -1.17 90) (layer "B.Fab")
        (effects (font (size 1 1) (thickness 0.15)) (justify mirror))
    )
    (fp_text user "${REFERENCE}" (at 0 0 90) (layer "B.Fab")
        (effects (font (size 0.25 0.25) (thickness 0.04)) (justify mirror))
    )
    (fp_text user "License: Apache-2.0" (at -0.939 -5.799 270) (layer "B.Fab") hide
        (effects (font (size 0.7 0.7) (thickness 0.15)) (justify left bottom mirror))
    )
    (fp_text user "Author: Antmicro" (at -0.939 -3.399 270) (layer "B.Fab") hide
        (effects (font (size 0.7 0.7) (thickness 0.15)) (justify left bottom mirror))
    )
    (fp_rect (start -0.925 0.47) (end 0.925 -0.47)
      (stroke (width 0.05) (type default)) (fill none) (layer "B.CrtYd"))
    (fp_line (start -0.494 -0.248) (end -0.494 0.25)
      (stroke (width 0.15) (type solid)) (layer "B.Fab"))
    (fp_line (start -0.494 0.25) (end 0.504 0.25)
      (stroke (width 0.15) (type solid)) (layer "B.Fab"))
    (fp_line (start 0.504 -0.248) (end -0.494 -0.248)
      (stroke (width 0.15) (type solid)) (layer "B.Fab"))
    (fp_line (start 0.504 0.25) (end 0.504 -0.248)
      (stroke (width 0.15) (type solid)) (layer "B.Fab"))
    (pad "1" smd roundrect (at -0.48 0 90) (size 0.59 0.64) (layers "B.Cu" "B.Paste" "B.Mask") (roundrect_rratio 0.25)
      (net 1 "GND") (pintype "passive"))
    (pad "2" smd roundrect (at 0.48 0 90) (size 0.59 0.64) (layers "B.Cu" "B.Paste" "B.Mask") (roundrect_rratio 0.25)
      (net 3 "VCC1V35") (pintype "passive"))
  )
	(footprint "antmicro-footprints:C_0402_1005Metric" (layer "B.Cu")
    (at 97.68 138.47 90)
    (descr "Capacitor SMD 0402")
    (tags "capacitor SMD 0402")
    (property "Author" "Antmicro")
    (property "Dielectric" "X5R")
    (property "License" "Apache-2.0")
    (property "MPN" "GRM155R61H104KE14D")
    (property "Manufacturer" "Murata")
    (property "Public" "False")
    (property "Sheetfile" "fpga-banks.kicad_sch")
    (property "Sheetname" "FPGA banks")
    (property "Val" "100n")
    (property "Voltage" "50V")
    (property "ki_description" "SMD Multilayer Ceramic Capacitor, 0.1 µF, 50 V, 0402 [1005 Metric], ± 10%, X5R, GRM Series")
    (property "ki_keywords" "0402, SMT, CAPACITOR, PASSIVE, CERAMIC, MLCC")
    (attr smd)
    (fp_text reference "C57" (at 0.045 -2.03 270) (layer "B.SilkS")
        (effects (font (size 0.7 0.7) (thickness 0.15)) (justify mirror))
    )
    (fp_text value "C_100n_0402" (at 0 -1.17 270) (layer "B.Fab")
        (effects (font (size 1 1) (thickness 0.15)) (justify mirror))
    )
    (fp_text user "${REFERENCE}" (at 0 0 270) (layer "B.Fab")
        (effects (font (size 0.25 0.25) (thickness 0.04)) (justify mirror))
    )
    (fp_text user "Author: Antmicro" (at -0.939 -3.399 270) (layer "B.Fab") hide
        (effects (font (size 0.7 0.7) (thickness 0.15)) (justify left bottom mirror))
    )
    (fp_text user "License: Apache-2.0" (at -0.939 -5.799 270) (layer "B.Fab") hide
        (effects (font (size 0.7 0.7) (thickness 0.15)) (justify left bottom mirror))
    )
    (fp_rect (start -0.925 0.47) (end 0.925 -0.47)
      (stroke (width 0.05) (type default)) (fill none) (layer "B.CrtYd"))
    (fp_line (start -0.494 -0.248) (end -0.494 0.25)
      (stroke (width 0.15) (type solid)) (layer "B.Fab"))
    (fp_line (start -0.494 0.25) (end 0.504 0.25)
      (stroke (width 0.15) (type solid)) (layer "B.Fab"))
    (fp_line (start 0.504 -0.248) (end -0.494 -0.248)
      (stroke (width 0.15) (type solid)) (layer "B.Fab"))
    (fp_line (start 0.504 0.25) (end 0.504 -0.248)
      (stroke (width 0.15) (type solid)) (layer "B.Fab"))
    (pad "1" smd roundrect (at -0.48 0 90) (size 0.59 0.64) (layers "B.Cu" "B.Paste" "B.Mask") (roundrect_rratio 0.25)
      (net 106 "PCIE_BMC_TX_DN") (pintype "passive"))
    (pad "2" smd roundrect (at 0.48 0 90) (size 0.59 0.64) (layers "B.Cu" "B.Paste" "B.Mask") (roundrect_rratio 0.25)
      (net 686 "/FPGA banks/PCIE_BMC_TX_C_DN") (pintype "passive"))
  )
)
